(kicad_pcb
	(version 20260206)
	(generator "pcbnew")
	(generator_version "10.0")
	(general
		(thickness 1.6)
		(legacy_teardrops no)
	)
	(paper "A4")
	(title_block
		(title "04192023_DAF0TMB3IC0_F0TG_MB_C_brd_V02_OCP.brd")
		(comment 1 "Grand Teton / footprints 1141-1146 of 8354")
	)
	(layers
		(0 "F.Cu" signal "TOP")
		(4 "In1.Cu" signal "GND")
		(6 "In2.Cu" signal "IN1")
		(8 "In3.Cu" signal "GND1")
		(10 "In4.Cu" signal "IN2")
		(12 "In5.Cu" signal "GND2")
		(14 "In6.Cu" signal "IN3")
		(16 "In7.Cu" signal "GND3")
		(18 "In8.Cu" signal "VCC")
		(20 "In9.Cu" signal "VCC1")
		(22 "In10.Cu" signal "GND4")
		(24 "In11.Cu" signal "IN4")
		(26 "In12.Cu" signal "GND5")
		(28 "In13.Cu" signal "IN5")
		(30 "In14.Cu" signal "GND6")
		(32 "In15.Cu" signal "IN6")
		(34 "In16.Cu" signal "GND7")
		(2 "B.Cu" signal "BOTTOM")
		(9 "F.Adhes" user "F.Adhesive")
		(11 "B.Adhes" user "B.Adhesive")
		(13 "F.Paste" user "Package Geometry/Pastemask Top")
		(15 "B.Paste" user "Package Geometry/Pastemask Bottom")
		(5 "F.SilkS" user "Ref Des/Silkscreen Top")
		(7 "B.SilkS" user "Ref Des/Silkscreen Bottom")
		(1 "F.Mask" user "Board Geometry/Soldermask Top")
		(3 "B.Mask" user "Board Geometry/Soldermask Bottom")
		(17 "Dwgs.User" user "User.Drawings")
		(19 "Cmts.User" user "User.Comments")
		(21 "Eco1.User" user "User.Eco1")
		(23 "Eco2.User" user "User.Eco2")
		(25 "Edge.Cuts" user "Board Geometry/Outline")
		(27 "Margin" user)
		(31 "F.CrtYd" user "Package Geometry/Place Bound Top")
		(29 "B.CrtYd" user "Package Geometry/Place Bound Bottom")
		(35 "F.Fab" user "Ref Des/Assembly Top")
		(33 "B.Fab" user "Ref Des/Assembly Bottom")
	)
	(footprint ""
		(layer "F.Cu")
		(at 95.433642 -35.279838)
		(property "Reference" "U219"
			(at -1.20904 2.445512 0)
			(unlocked yes)
			(layer "F.SilkS")
			(effects
				(font
					(size 0.7874 0.5842)
					(thickness 0.1524)
				)
				(justify left)
			)
		)
		(property "Value" ""
			(at 0 0 0)
			(layer "F.Fab")
			(effects
				(font
					(size 1.27 1.27)
				)
			)
		)
		(duplicate_pad_numbers_are_jumpers no)
		(fp_line
			(start -1.733296 -1.549908)
			(end -1.733296 1.549908)
			(stroke
				(width 0.1524)
				(type default)
			)
			(layer "F.SilkS")
		)
		(fp_line
			(start -1.733296 1.549908)
			(end 1.733296 1.549908)
			(stroke
				(width 0.1524)
				(type default)
			)
			(layer "F.SilkS")
		)
		(fp_line
			(start -0.660908 -1.549908)
			(end -1.733296 -1.549908)
			(stroke
				(width 0.1524)
				(type default)
			)
			(layer "F.SilkS")
		)
		(fp_line
			(start 0 -0.889)
			(end -0.660908 -1.549908)
			(stroke
				(width 0.1524)
				(type default)
			)
			(layer "F.SilkS")
		)
		(fp_line
			(start 0.660908 -1.549908)
			(end 0 -0.889)
			(stroke
				(width 0.1524)
				(type default)
			)
			(layer "F.SilkS")
		)
		(fp_line
			(start 1.733296 -1.549908)
			(end 0.660908 -1.549908)
			(stroke
				(width 0.1524)
				(type default)
			)
			(layer "F.SilkS")
		)
		(fp_line
			(start 1.733296 1.549908)
			(end 1.733296 -1.549908)
			(stroke
				(width 0.1524)
				(type default)
			)
			(layer "F.SilkS")
		)
		(fp_poly
			(pts
				(xy -2.4384 -0.69596) (xy -2.4384 -1.20396) (xy -1.9304 -0.94996)
			)
			(stroke
				(width 0)
				(type default)
			)
			(fill yes)
			(layer "F.SilkS")
		)
		(fp_line
			(start -0.849884 -1.549908)
			(end -0.849884 1.549908)
			(stroke
				(width 0.1)
				(type default)
			)
			(layer "F.Fab")
		)
		(fp_line
			(start -0.849884 1.549908)
			(end 0.849884 1.549908)
			(stroke
				(width 0.1)
				(type default)
			)
			(layer "F.Fab")
		)
		(fp_line
			(start 0.849884 -1.549908)
			(end -0.849884 -1.549908)
			(stroke
				(width 0.1)
				(type default)
			)
			(layer "F.Fab")
		)
		(fp_line
			(start 0.849884 1.549908)
			(end 0.849884 -1.549908)
			(stroke
				(width 0.1)
				(type default)
			)
			(layer "F.Fab")
		)
		(fp_poly
			(pts
				(xy -2.4384 -1.20396) (xy -2.4384 -0.69596) (xy -1.9304 -0.94996)
			)
			(stroke
				(width 0)
				(type default)
			)
			(fill yes)
			(layer "F.Fab")
		)
		(pad "1" smd rect
			(at -1.199896 -0.94996 270)
			(size 0.5588 0.8128)
			(layers "F.Cu" "F.Mask" "F.Paste")
			(net "NC_U219_NC1")
		)
		(pad "2" smd rect
			(at -1.199896 0 270)
			(size 0.5588 0.8128)
			(layers "F.Cu" "F.Mask" "F.Paste")
			(net "OCP_V3_2_WAKE_BUFF_R_N")
		)
		(pad "3" smd rect
			(at -1.199896 0.94996 270)
			(size 0.5588 0.8128)
			(layers "F.Cu" "F.Mask" "F.Paste")
			(net "GND")
		)
		(pad "4" smd rect
			(at 1.199896 0.94996 270)
			(size 0.5588 0.8128)
			(layers "F.Cu" "F.Mask" "F.Paste")
			(net "IRQ_LVC3_V3_2_WAKE_BUF_N")
		)
		(pad "5" smd rect
			(at 1.199896 -0.94996 270)
			(size 0.5588 0.8128)
			(layers "F.Cu" "F.Mask" "F.Paste")
			(net "P3V3_AUX")
		)
	)
	(footprint ""
		(layer "F.Cu")
		(at 288.325306 -349.381572 90)
		(property "Reference" "PC142"
			(at 0 0 90)
			(layer "F.SilkS")
			(hide yes)
			(effects
				(font
					(size 1.27 1.27)
				)
			)
		)
		(property "Value" ""
			(at 0 0 90)
			(layer "F.Fab")
			(effects
				(font
					(size 1.27 1.27)
				)
			)
		)
		(duplicate_pad_numbers_are_jumpers no)
		(fp_line
			(start 0.7874 -0.4064)
			(end 0.7874 0.4064)
			(stroke
				(width 0.1524)
				(type default)
			)
			(layer "F.SilkS")
		)
		(fp_line
			(start -0.7874 -0.4064)
			(end 0.7874 -0.4064)
			(stroke
				(width 0.1524)
				(type default)
			)
			(layer "F.SilkS")
		)
		(fp_line
			(start 0.7874 0.4064)
			(end 0.376428 0.4064)
			(stroke
				(width 0.1524)
				(type default)
			)
			(layer "F.SilkS")
		)
		(fp_line
			(start -0.258572 0.4064)
			(end -0.7874 0.4064)
			(stroke
				(width 0.1524)
				(type default)
			)
			(layer "F.SilkS")
		)
		(fp_line
			(start -0.7874 0.4064)
			(end -0.7874 -0.4064)
			(stroke
				(width 0.1524)
				(type default)
			)
			(layer "F.SilkS")
		)
		(fp_line
			(start -0.12065 -0.305054)
			(end -0.12065 -0.2794)
			(stroke
				(width 0.1)
				(type default)
			)
			(layer "F.Fab")
		)
		(fp_line
			(start -0.67945 -0.305054)
			(end -0.12065 -0.305054)
			(stroke
				(width 0.1)
				(type default)
			)
			(layer "F.Fab")
		)
		(fp_line
			(start 0.67945 -0.3048)
			(end 0.67945 0.3048)
			(stroke
				(width 0.1)
				(type default)
			)
			(layer "F.Fab")
		)
		(fp_line
			(start 0.12065 -0.3048)
			(end 0.67945 -0.3048)
			(stroke
				(width 0.1)
				(type default)
			)
			(layer "F.Fab")
		)
		(fp_line
			(start 0.12065 -0.2794)
			(end 0.12065 -0.3048)
			(stroke
				(width 0.1)
				(type default)
			)
			(layer "F.Fab")
		)
		(fp_line
			(start -0.12065 -0.2794)
			(end 0.12065 -0.2794)
			(stroke
				(width 0.1)
				(type default)
			)
			(layer "F.Fab")
		)
		(fp_line
			(start 0.120396 0.2794)
			(end -0.12065 0.2794)
			(stroke
				(width 0.1)
				(type default)
			)
			(layer "F.Fab")
		)
		(fp_line
			(start -0.12065 0.2794)
			(end -0.12065 0.3048)
			(stroke
				(width 0.1)
				(type default)
			)
			(layer "F.Fab")
		)
		(fp_line
			(start 0.67945 0.3048)
			(end 0.120396 0.3048)
			(stroke
				(width 0.1)
				(type default)
			)
			(layer "F.Fab")
		)
		(fp_line
			(start 0.120396 0.3048)
			(end 0.120396 0.2794)
			(stroke
				(width 0.1)
				(type default)
			)
			(layer "F.Fab")
		)
		(fp_line
			(start -0.12065 0.3048)
			(end -0.67945 0.3048)
			(stroke
				(width 0.1)
				(type default)
			)
			(layer "F.Fab")
		)
		(fp_line
			(start -0.67945 0.3048)
			(end -0.67945 -0.305054)
			(stroke
				(width 0.1)
				(type default)
			)
			(layer "F.Fab")
		)
		(pad "1" smd circle
			(at -0.40005 0 90)
			(size 0 0)
			(layers "F.Cu" "F.Mask" "F.Paste")
			(net "PVDDIO_P0_VCC2")
		)
		(pad "2" smd circle
			(at 0.40005 0 90)
			(size 0 0)
			(layers "F.Cu" "F.Mask" "F.Paste")
			(net "GND")
		)
	)
	(footprint ""
		(layer "F.Cu")
		(at 254.362966 -74.44105)
		(property "Reference" "U134"
			(at -1.4732 -1.768348 0)
			(unlocked yes)
			(layer "F.SilkS")
			(effects
				(font
					(size 0.7874 0.5842)
					(thickness 0.1524)
				)
				(justify left)
			)
		)
		(property "Value" ""
			(at 0 0 0)
			(layer "F.Fab")
			(effects
				(font
					(size 1.27 1.27)
				)
			)
		)
		(duplicate_pad_numbers_are_jumpers no)
		(fp_line
			(start -1.38176 -1.100074)
			(end -1.38176 1.100074)
			(stroke
				(width 0.1524)
				(type default)
			)
			(layer "F.SilkS")
		)
		(fp_line
			(start -1.38176 1.100074)
			(end 1.38176 1.100074)
			(stroke
				(width 0.1524)
				(type default)
			)
			(layer "F.SilkS")
		)
		(fp_line
			(start -0.592074 -1.100074)
			(end -1.38176 -1.100074)
			(stroke
				(width 0.1524)
				(type default)
			)
			(layer "F.SilkS")
		)
		(fp_line
			(start 0 -0.508)
			(end -0.592074 -1.100074)
			(stroke
				(width 0.1524)
				(type default)
			)
			(layer "F.SilkS")
		)
		(fp_line
			(start 0.592074 -1.100074)
			(end 0 -0.508)
			(stroke
				(width 0.1524)
				(type default)
			)
			(layer "F.SilkS")
		)
		(fp_line
			(start 1.38176 -1.100074)
			(end 0.592074 -1.100074)
			(stroke
				(width 0.1524)
				(type default)
			)
			(layer "F.SilkS")
		)
		(fp_line
			(start 1.38176 1.100074)
			(end 1.38176 -1.100074)
			(stroke
				(width 0.1524)
				(type default)
			)
			(layer "F.SilkS")
		)
		(fp_poly
			(pts
				(xy -2.041652 -1.321308) (xy -1.735328 -1.637792) (xy -1.572006 -1.172972)
			)
			(stroke
				(width 0)
				(type default)
			)
			(fill yes)
			(layer "F.SilkS")
		)
		(fp_line
			(start -0.674878 -1.100074)
			(end -0.674878 1.100074)
			(stroke
				(width 0.1)
				(type default)
			)
			(layer "F.Fab")
		)
		(fp_line
			(start -0.674878 1.100074)
			(end 0.674878 1.100074)
			(stroke
				(width 0.1)
				(type default)
			)
			(layer "F.Fab")
		)
		(fp_line
			(start 0.674878 -1.100074)
			(end -0.674878 -1.100074)
			(stroke
				(width 0.1)
				(type default)
			)
			(layer "F.Fab")
		)
		(fp_line
			(start 0.674878 1.100074)
			(end 0.674878 -1.100074)
			(stroke
				(width 0.1)
				(type default)
			)
			(layer "F.Fab")
		)
		(fp_poly
			(pts
				(xy -1.9431 -0.870204) (xy -1.50241 -0.649986) (xy -1.9431 -0.429768)
			)
			(stroke
				(width 0)
				(type default)
			)
			(fill yes)
			(layer "F.Fab")
		)
		(pad "1" smd rect
			(at -0.94996 -0.649986 270)
			(size 0.4318 0.6096)
			(layers "F.Cu" "F.Mask" "F.Paste")
			(net "RST_SMB_E1S_N")
		)
		(pad "2" smd rect
			(at -0.94996 0 270)
			(size 0.4318 0.6096)
			(layers "F.Cu" "F.Mask" "F.Paste")
			(net "GND")
		)
		(pad "3" smd rect
			(at -0.94996 0.649986 270)
			(size 0.4318 0.6096)
			(layers "F.Cu" "F.Mask" "F.Paste")
			(net "RST_SMB_E1S_N")
		)
		(pad "4" smd rect
			(at 0.94996 0.649986 270)
			(size 0.4318 0.6096)
			(layers "F.Cu" "F.Mask" "F.Paste")
			(net "SMB_PCIE_E1S_ISO_EN_R2")
		)
		(pad "5" smd rect
			(at 0.94996 0 270)
			(size 0.4318 0.6096)
			(layers "F.Cu" "F.Mask" "F.Paste")
			(net "P3V3_AUX")
		)
		(pad "6" smd rect
			(at 0.94996 -0.649986 270)
			(size 0.4318 0.6096)
			(layers "F.Cu" "F.Mask" "F.Paste")
			(net "RST_SMB_BUF_E1S_0_N")
		)
	)
	(footprint ""
		(layer "F.Cu")
		(at 376.89028 -32.323532 -90)
		(property "Reference" "C2344"
			(at 0 0 270)
			(layer "F.SilkS")
			(hide yes)
			(effects
				(font
					(size 1.27 1.27)
				)
			)
		)
		(property "Value" ""
			(at 0 0 270)
			(layer "F.Fab")
			(effects
				(font
					(size 1.27 1.27)
				)
			)
		)
		(duplicate_pad_numbers_are_jumpers no)
		(fp_line
			(start -0.7874 0.4064)
			(end -0.7874 -0.4064)
			(stroke
				(width 0.1524)
				(type default)
			)
			(layer "F.SilkS")
		)
		(fp_line
			(start 0.7874 0.4064)
			(end -0.7874 0.4064)
			(stroke
				(width 0.1524)
				(type default)
			)
			(layer "F.SilkS")
		)
		(fp_line
			(start -0.7874 -0.4064)
			(end 0.7874 -0.4064)
			(stroke
				(width 0.1524)
				(type default)
			)
			(layer "F.SilkS")
		)
		(fp_line
			(start 0.7874 -0.4064)
			(end 0.7874 0.4064)
			(stroke
				(width 0.1524)
				(type default)
			)
			(layer "F.SilkS")
		)
		(fp_line
			(start -0.67945 0.3048)
			(end -0.67945 -0.305054)
			(stroke
				(width 0.1)
				(type default)
			)
			(layer "F.Fab")
		)
		(fp_line
			(start -0.12065 0.3048)
			(end -0.67945 0.3048)
			(stroke
				(width 0.1)
				(type default)
			)
			(layer "F.Fab")
		)
		(fp_line
			(start 0.120396 0.3048)
			(end 0.120396 0.2794)
			(stroke
				(width 0.1)
				(type default)
			)
			(layer "F.Fab")
		)
		(fp_line
			(start 0.67945 0.3048)
			(end 0.120396 0.3048)
			(stroke
				(width 0.1)
				(type default)
			)
			(layer "F.Fab")
		)
		(fp_line
			(start -0.12065 0.2794)
			(end -0.12065 0.3048)
			(stroke
				(width 0.1)
				(type default)
			)
			(layer "F.Fab")
		)
		(fp_line
			(start 0.120396 0.2794)
			(end -0.12065 0.2794)
			(stroke
				(width 0.1)
				(type default)
			)
			(layer "F.Fab")
		)
		(fp_line
			(start -0.12065 -0.2794)
			(end 0.12065 -0.2794)
			(stroke
				(width 0.1)
				(type default)
			)
			(layer "F.Fab")
		)
		(fp_line
			(start 0.12065 -0.2794)
			(end 0.12065 -0.3048)
			(stroke
				(width 0.1)
				(type default)
			)
			(layer "F.Fab")
		)
		(fp_line
			(start 0.12065 -0.3048)
			(end 0.67945 -0.3048)
			(stroke
				(width 0.1)
				(type default)
			)
			(layer "F.Fab")
		)
		(fp_line
			(start 0.67945 -0.3048)
			(end 0.67945 0.3048)
			(stroke
				(width 0.1)
				(type default)
			)
			(layer "F.Fab")
		)
		(fp_line
			(start -0.67945 -0.305054)
			(end -0.12065 -0.305054)
			(stroke
				(width 0.1)
				(type default)
			)
			(layer "F.Fab")
		)
		(fp_line
			(start -0.12065 -0.305054)
			(end -0.12065 -0.2794)
			(stroke
				(width 0.1)
				(type default)
			)
			(layer "F.Fab")
		)
		(pad "1" smd circle
			(at -0.40005 0 270)
			(size 0 0)
			(layers "F.Cu" "F.Mask" "F.Paste")
			(net "P3V3_AUX")
		)
		(pad "2" smd circle
			(at 0.40005 0 270)
			(size 0 0)
			(layers "F.Cu" "F.Mask" "F.Paste")
			(net "GND")
		)
	)
	(footprint ""
		(layer "F.Cu")
		(at 294.421052 -116.253514)
		(property "Reference" "R2566"
			(at 0 0 0)
			(layer "F.SilkS")
			(hide yes)
			(effects
				(font
					(size 1.27 1.27)
				)
			)
		)
		(property "Value" ""
			(at 0 0 0)
			(layer "F.Fab")
			(effects
				(font
					(size 1.27 1.27)
				)
			)
		)
		(duplicate_pad_numbers_are_jumpers no)
		(fp_line
			(start -0.7874 -0.4064)
			(end 0.7874 -0.4064)
			(stroke
				(width 0.1524)
				(type default)
			)
			(layer "F.SilkS")
		)
		(fp_line
			(start -0.7874 0.4064)
			(end -0.7874 -0.4064)
			(stroke
				(width 0.1524)
				(type default)
			)
			(layer "F.SilkS")
		)
		(fp_line
			(start 0.7874 -0.4064)
			(end 0.7874 0.4064)
			(stroke
				(width 0.1524)
				(type default)
			)
			(layer "F.SilkS")
		)
		(fp_line
			(start 0.7874 0.4064)
			(end -0.7874 0.4064)
			(stroke
				(width 0.1524)
				(type default)
			)
			(layer "F.SilkS")
		)
		(fp_line
			(start -0.67945 -0.305054)
			(end -0.12065 -0.305054)
			(stroke
				(width 0.1)
				(type default)
			)
			(layer "F.Fab")
		)
		(fp_line
			(start -0.67945 0.3048)
			(end -0.67945 -0.305054)
			(stroke
				(width 0.1)
				(type default)
			)
			(layer "F.Fab")
		)
		(fp_line
			(start -0.12065 -0.305054)
			(end -0.12065 -0.2794)
			(stroke
				(width 0.1)
				(type default)
			)
			(layer "F.Fab")
		)
		(fp_line
			(start -0.12065 -0.2794)
			(end 0.12065 -0.2794)
			(stroke
				(width 0.1)
				(type default)
			)
			(layer "F.Fab")
		)
		(fp_line
			(start -0.12065 0.2794)
			(end -0.12065 0.3048)
			(stroke
				(width 0.1)
				(type default)
			)
			(layer "F.Fab")
		)
		(fp_line
			(start -0.12065 0.3048)
			(end -0.67945 0.3048)
			(stroke
				(width 0.1)
				(type default)
			)
			(layer "F.Fab")
		)
		(fp_line
			(start 0.120396 0.2794)
			(end -0.12065 0.2794)
			(stroke
				(width 0.1)
				(type default)
			)
			(layer "F.Fab")
		)
		(fp_line
			(start 0.120396 0.3048)
			(end 0.120396 0.2794)
			(stroke
				(width 0.1)
				(type default)
			)
			(layer "F.Fab")
		)
		(fp_line
			(start 0.12065 -0.3048)
			(end 0.67945 -0.3048)
			(stroke
				(width 0.1)
				(type default)
			)
			(layer "F.Fab")
		)
		(fp_line
			(start 0.12065 -0.2794)
			(end 0.12065 -0.3048)
			(stroke
				(width 0.1)
				(type default)
			)
			(layer "F.Fab")
		)
		(fp_line
			(start 0.67945 -0.3048)
			(end 0.67945 0.3048)
			(stroke
				(width 0.1)
				(type default)
			)
			(layer "F.Fab")
		)
		(fp_line
			(start 0.67945 0.3048)
			(end 0.120396 0.3048)
			(stroke
				(width 0.1)
				(type default)
			)
			(layer "F.Fab")
		)
		(pad "1" smd circle
			(at -0.40005 0)
			(size 0 0)
			(layers "F.Cu" "F.Mask" "F.Paste")
			(net "SMB_FRU_3V3AUX_SDA_R")
		)
		(pad "2" smd circle
			(at 0.40005 0)
			(size 0 0)
			(layers "F.Cu" "F.Mask" "F.Paste")
			(net "SMB_FRU_3V3AUX_SDA")
		)
	)
	(footprint ""
		(layer "F.Cu")
		(at 181.991 -129.377948 -90)
		(property "Reference" "R57"
			(at 0 0 270)
			(layer "F.SilkS")
			(hide yes)
			(effects
				(font
					(size 1.27 1.27)
				)
			)
		)
		(property "Value" ""
			(at 0 0 270)
			(layer "F.Fab")
			(effects
				(font
					(size 1.27 1.27)
				)
			)
		)
		(duplicate_pad_numbers_are_jumpers no)
		(fp_line
			(start -0.7874 0.4064)
			(end -0.7874 -0.4064)
			(stroke
				(width 0.1524)
				(type default)
			)
			(layer "F.SilkS")
		)
		(fp_line
			(start 0.7874 0.4064)
			(end -0.7874 0.4064)
			(stroke
				(width 0.1524)
				(type default)
			)
			(layer "F.SilkS")
		)
		(fp_line
			(start -0.7874 -0.4064)
			(end 0.7874 -0.4064)
			(stroke
				(width 0.1524)
				(type default)
			)
			(layer "F.SilkS")
		)
		(fp_line
			(start 0.7874 -0.4064)
			(end 0.7874 0.4064)
			(stroke
				(width 0.1524)
				(type default)
			)
			(layer "F.SilkS")
		)
		(fp_line
			(start -0.67945 0.3048)
			(end -0.67945 -0.305054)
			(stroke
				(width 0.1)
				(type default)
			)
			(layer "F.Fab")
		)
		(fp_line
			(start -0.12065 0.3048)
			(end -0.67945 0.3048)
			(stroke
				(width 0.1)
				(type default)
			)
			(layer "F.Fab")
		)
		(fp_line
			(start 0.120396 0.3048)
			(end 0.120396 0.2794)
			(stroke
				(width 0.1)
				(type default)
			)
			(layer "F.Fab")
		)
		(fp_line
			(start 0.67945 0.3048)
			(end 0.120396 0.3048)
			(stroke
				(width 0.1)
				(type default)
			)
			(layer "F.Fab")
		)
		(fp_line
			(start -0.12065 0.2794)
			(end -0.12065 0.3048)
			(stroke
				(width 0.1)
				(type default)
			)
			(layer "F.Fab")
		)
		(fp_line
			(start 0.120396 0.2794)
			(end -0.12065 0.2794)
			(stroke
				(width 0.1)
				(type default)
			)
			(layer "F.Fab")
		)
		(fp_line
			(start -0.12065 -0.2794)
			(end 0.12065 -0.2794)
			(stroke
				(width 0.1)
				(type default)
			)
			(layer "F.Fab")
		)
		(fp_line
			(start 0.12065 -0.2794)
			(end 0.12065 -0.3048)
			(stroke
				(width 0.1)
				(type default)
			)
			(layer "F.Fab")
		)
		(fp_line
			(start 0.12065 -0.3048)
			(end 0.67945 -0.3048)
			(stroke
				(width 0.1)
				(type default)
			)
			(layer "F.Fab")
		)
		(fp_line
			(start 0.67945 -0.3048)
			(end 0.67945 0.3048)
			(stroke
				(width 0.1)
				(type default)
			)
			(layer "F.Fab")
		)
		(fp_line
			(start -0.67945 -0.305054)
			(end -0.12065 -0.305054)
			(stroke
				(width 0.1)
				(type default)
			)
			(layer "F.Fab")
		)
		(fp_line
			(start -0.12065 -0.305054)
			(end -0.12065 -0.2794)
			(stroke
				(width 0.1)
				(type default)
			)
			(layer "F.Fab")
		)
		(pad "1" smd circle
			(at -0.40005 0 270)
			(size 0 0)
			(layers "F.Cu" "F.Mask" "F.Paste")
			(net "RST_CPU1_RESETL_N")
		)
		(pad "2" smd circle
			(at 0.40005 0 270)
			(size 0 0)
			(layers "F.Cu" "F.Mask" "F.Paste")
			(net "FM_RST_CPU1_RESETL_N")
		)
	)
)
